(kicad_pcb
	(version 20260206)
	(generator "pcbnew")
	(generator_version "10.0")
	(general
		(thickness 1.6)
		(legacy_teardrops no)
	)
	(paper "A4")
	(title_block
		(title "01162023_DA0F0TEBIF0_F0T_Expander_BD_F_brd_V02_OCP.brd")
		(comment 1 "Grand Teton / footprints 6572-6577 of 9728")
	)
	(layers
		(0 "F.Cu" signal "TOP")
		(4 "In1.Cu" signal "GND")
		(6 "In2.Cu" signal "VCC")
		(8 "In3.Cu" signal "VCC1")
		(10 "In4.Cu" signal "GND1")
		(12 "In5.Cu" signal "IN1")
		(14 "In6.Cu" signal "GND2")
		(16 "In7.Cu" signal "IN2")
		(18 "In8.Cu" signal "GND3")
		(20 "In9.Cu" signal "IN3")
		(22 "In10.Cu" signal "GND4")
		(24 "In11.Cu" signal "IN4")
		(26 "In12.Cu" signal "GND5")
		(28 "In13.Cu" signal "IN5")
		(30 "In14.Cu" signal "GND6")
		(32 "In15.Cu" signal "IN6")
		(34 "In16.Cu" signal "GND7")
		(2 "B.Cu" signal "BOTTOM")
		(9 "F.Adhes" user "F.Adhesive")
		(11 "B.Adhes" user "B.Adhesive")
		(13 "F.Paste" user "Package Geometry/Pastemask Top")
		(15 "B.Paste" user "Package Geometry/Pastemask Bottom")
		(5 "F.SilkS" user "Ref Des/Silkscreen Top")
		(7 "B.SilkS" user "Ref Des/Silkscreen Bottom")
		(1 "F.Mask" user "Board Geometry/Soldermask Top")
		(3 "B.Mask" user "Board Geometry/Soldermask Bottom")
		(17 "Dwgs.User" user "User.Drawings")
		(19 "Cmts.User" user "User.Comments")
		(21 "Eco1.User" user "User.Eco1")
		(23 "Eco2.User" user "User.Eco2")
		(25 "Edge.Cuts" user "Board Geometry/Outline")
		(27 "Margin" user)
		(31 "F.CrtYd" user "Package Geometry/Place Bound Top")
		(29 "B.CrtYd" user "Package Geometry/Place Bound Bottom")
		(35 "F.Fab" user "Ref Des/Assembly Top")
		(33 "B.Fab" user "Ref Des/Assembly Bottom")
	)
	(footprint ""
		(layer "F.Cu")
		(at 97.850198 -95.263716 -90)
		(property "Reference" "PR197"
			(at 0 0 270)
			(layer "F.SilkS")
			(hide yes)
			(effects
				(font
					(size 1.27 1.27)
				)
			)
		)
		(property "Value" ""
			(at 0 0 270)
			(layer "F.Fab")
			(effects
				(font
					(size 1.27 1.27)
				)
			)
		)
		(duplicate_pad_numbers_are_jumpers no)
		(fp_line
			(start -0.7874 0.4064)
			(end -0.7874 -0.4064)
			(stroke
				(width 0.1524)
				(type default)
			)
			(layer "F.SilkS")
		)
		(fp_line
			(start 0.7874 0.4064)
			(end -0.7874 0.4064)
			(stroke
				(width 0.1524)
				(type default)
			)
			(layer "F.SilkS")
		)
		(fp_line
			(start -0.7874 -0.4064)
			(end 0.7874 -0.4064)
			(stroke
				(width 0.1524)
				(type default)
			)
			(layer "F.SilkS")
		)
		(fp_line
			(start 0.7874 -0.4064)
			(end 0.7874 0.4064)
			(stroke
				(width 0.1524)
				(type default)
			)
			(layer "F.SilkS")
		)
		(fp_line
			(start -0.67945 0.3048)
			(end -0.67945 -0.305054)
			(stroke
				(width 0.1)
				(type default)
			)
			(layer "F.Fab")
		)
		(fp_line
			(start -0.12065 0.3048)
			(end -0.67945 0.3048)
			(stroke
				(width 0.1)
				(type default)
			)
			(layer "F.Fab")
		)
		(fp_line
			(start 0.120396 0.3048)
			(end 0.120396 0.2794)
			(stroke
				(width 0.1)
				(type default)
			)
			(layer "F.Fab")
		)
		(fp_line
			(start 0.67945 0.3048)
			(end 0.120396 0.3048)
			(stroke
				(width 0.1)
				(type default)
			)
			(layer "F.Fab")
		)
		(fp_line
			(start -0.12065 0.2794)
			(end -0.12065 0.3048)
			(stroke
				(width 0.1)
				(type default)
			)
			(layer "F.Fab")
		)
		(fp_line
			(start 0.120396 0.2794)
			(end -0.12065 0.2794)
			(stroke
				(width 0.1)
				(type default)
			)
			(layer "F.Fab")
		)
		(fp_line
			(start -0.12065 -0.2794)
			(end 0.12065 -0.2794)
			(stroke
				(width 0.1)
				(type default)
			)
			(layer "F.Fab")
		)
		(fp_line
			(start 0.12065 -0.2794)
			(end 0.12065 -0.3048)
			(stroke
				(width 0.1)
				(type default)
			)
			(layer "F.Fab")
		)
		(fp_line
			(start 0.12065 -0.3048)
			(end 0.67945 -0.3048)
			(stroke
				(width 0.1)
				(type default)
			)
			(layer "F.Fab")
		)
		(fp_line
			(start 0.67945 -0.3048)
			(end 0.67945 0.3048)
			(stroke
				(width 0.1)
				(type default)
			)
			(layer "F.Fab")
		)
		(fp_line
			(start -0.67945 -0.305054)
			(end -0.12065 -0.305054)
			(stroke
				(width 0.1)
				(type default)
			)
			(layer "F.Fab")
		)
		(fp_line
			(start -0.12065 -0.305054)
			(end -0.12065 -0.2794)
			(stroke
				(width 0.1)
				(type default)
			)
			(layer "F.Fab")
		)
		(pad "1" smd circle
			(at -0.40005 0 270)
			(size 0 0)
			(layers "F.Cu" "F.Mask" "F.Paste")
			(net "P12V_NIC1_OCP")
		)
		(pad "2" smd circle
			(at 0.40005 0 270)
			(size 0 0)
			(layers "F.Cu" "F.Mask" "F.Paste")
			(net "GND")
		)
	)
	(footprint ""
		(layer "F.Cu")
		(at 407.190448 -373.881142)
		(property "Reference" "R6682"
			(at 0 0 0)
			(layer "F.SilkS")
			(hide yes)
			(effects
				(font
					(size 1.27 1.27)
				)
			)
		)
		(property "Value" ""
			(at 0 0 0)
			(layer "F.Fab")
			(effects
				(font
					(size 1.27 1.27)
				)
			)
		)
		(duplicate_pad_numbers_are_jumpers no)
		(fp_line
			(start -0.7874 -0.4064)
			(end 0.7874 -0.4064)
			(stroke
				(width 0.1524)
				(type default)
			)
			(layer "F.SilkS")
		)
		(fp_line
			(start -0.7874 0.4064)
			(end -0.7874 -0.4064)
			(stroke
				(width 0.1524)
				(type default)
			)
			(layer "F.SilkS")
		)
		(fp_line
			(start 0.7874 -0.4064)
			(end 0.7874 0.4064)
			(stroke
				(width 0.1524)
				(type default)
			)
			(layer "F.SilkS")
		)
		(fp_line
			(start 0.7874 0.4064)
			(end -0.7874 0.4064)
			(stroke
				(width 0.1524)
				(type default)
			)
			(layer "F.SilkS")
		)
		(fp_line
			(start -0.67945 -0.305054)
			(end -0.12065 -0.305054)
			(stroke
				(width 0.1)
				(type default)
			)
			(layer "F.Fab")
		)
		(fp_line
			(start -0.67945 0.3048)
			(end -0.67945 -0.305054)
			(stroke
				(width 0.1)
				(type default)
			)
			(layer "F.Fab")
		)
		(fp_line
			(start -0.12065 -0.305054)
			(end -0.12065 -0.2794)
			(stroke
				(width 0.1)
				(type default)
			)
			(layer "F.Fab")
		)
		(fp_line
			(start -0.12065 -0.2794)
			(end 0.12065 -0.2794)
			(stroke
				(width 0.1)
				(type default)
			)
			(layer "F.Fab")
		)
		(fp_line
			(start -0.12065 0.2794)
			(end -0.12065 0.3048)
			(stroke
				(width 0.1)
				(type default)
			)
			(layer "F.Fab")
		)
		(fp_line
			(start -0.12065 0.3048)
			(end -0.67945 0.3048)
			(stroke
				(width 0.1)
				(type default)
			)
			(layer "F.Fab")
		)
		(fp_line
			(start 0.120396 0.2794)
			(end -0.12065 0.2794)
			(stroke
				(width 0.1)
				(type default)
			)
			(layer "F.Fab")
		)
		(fp_line
			(start 0.120396 0.3048)
			(end 0.120396 0.2794)
			(stroke
				(width 0.1)
				(type default)
			)
			(layer "F.Fab")
		)
		(fp_line
			(start 0.12065 -0.3048)
			(end 0.67945 -0.3048)
			(stroke
				(width 0.1)
				(type default)
			)
			(layer "F.Fab")
		)
		(fp_line
			(start 0.12065 -0.2794)
			(end 0.12065 -0.3048)
			(stroke
				(width 0.1)
				(type default)
			)
			(layer "F.Fab")
		)
		(fp_line
			(start 0.67945 -0.3048)
			(end 0.67945 0.3048)
			(stroke
				(width 0.1)
				(type default)
			)
			(layer "F.Fab")
		)
		(fp_line
			(start 0.67945 0.3048)
			(end 0.120396 0.3048)
			(stroke
				(width 0.1)
				(type default)
			)
			(layer "F.Fab")
		)
		(pad "1" smd circle
			(at -0.40005 0)
			(size 0 0)
			(layers "F.Cu" "F.Mask" "F.Paste")
			(net "GPU_3V3IO_RSVD1")
		)
		(pad "2" smd circle
			(at 0.40005 0)
			(size 0 0)
			(layers "F.Cu" "F.Mask" "F.Paste")
			(net "GND")
		)
	)
	(footprint ""
		(layer "F.Cu")
		(at 78.267814 -56.353456)
		(property "Reference" "C2865"
			(at 0 0 0)
			(layer "F.SilkS")
			(hide yes)
			(effects
				(font
					(size 1.27 1.27)
				)
			)
		)
		(property "Value" ""
			(at 0 0 0)
			(layer "F.Fab")
			(effects
				(font
					(size 1.27 1.27)
				)
			)
		)
		(duplicate_pad_numbers_are_jumpers no)
		(fp_line
			(start -0.7874 -0.4064)
			(end 0.7874 -0.4064)
			(stroke
				(width 0.1524)
				(type default)
			)
			(layer "F.SilkS")
		)
		(fp_line
			(start -0.7874 0.4064)
			(end -0.7874 -0.4064)
			(stroke
				(width 0.1524)
				(type default)
			)
			(layer "F.SilkS")
		)
		(fp_line
			(start 0.7874 -0.4064)
			(end 0.7874 0.4064)
			(stroke
				(width 0.1524)
				(type default)
			)
			(layer "F.SilkS")
		)
		(fp_line
			(start 0.7874 0.4064)
			(end -0.7874 0.4064)
			(stroke
				(width 0.1524)
				(type default)
			)
			(layer "F.SilkS")
		)
		(fp_line
			(start -0.67945 -0.305054)
			(end -0.12065 -0.305054)
			(stroke
				(width 0.1)
				(type default)
			)
			(layer "F.Fab")
		)
		(fp_line
			(start -0.67945 0.3048)
			(end -0.67945 -0.305054)
			(stroke
				(width 0.1)
				(type default)
			)
			(layer "F.Fab")
		)
		(fp_line
			(start -0.12065 -0.305054)
			(end -0.12065 -0.2794)
			(stroke
				(width 0.1)
				(type default)
			)
			(layer "F.Fab")
		)
		(fp_line
			(start -0.12065 -0.2794)
			(end 0.12065 -0.2794)
			(stroke
				(width 0.1)
				(type default)
			)
			(layer "F.Fab")
		)
		(fp_line
			(start -0.12065 0.2794)
			(end -0.12065 0.3048)
			(stroke
				(width 0.1)
				(type default)
			)
			(layer "F.Fab")
		)
		(fp_line
			(start -0.12065 0.3048)
			(end -0.67945 0.3048)
			(stroke
				(width 0.1)
				(type default)
			)
			(layer "F.Fab")
		)
		(fp_line
			(start 0.120396 0.2794)
			(end -0.12065 0.2794)
			(stroke
				(width 0.1)
				(type default)
			)
			(layer "F.Fab")
		)
		(fp_line
			(start 0.120396 0.3048)
			(end 0.120396 0.2794)
			(stroke
				(width 0.1)
				(type default)
			)
			(layer "F.Fab")
		)
		(fp_line
			(start 0.12065 -0.3048)
			(end 0.67945 -0.3048)
			(stroke
				(width 0.1)
				(type default)
			)
			(layer "F.Fab")
		)
		(fp_line
			(start 0.12065 -0.2794)
			(end 0.12065 -0.3048)
			(stroke
				(width 0.1)
				(type default)
			)
			(layer "F.Fab")
		)
		(fp_line
			(start 0.67945 -0.3048)
			(end 0.67945 0.3048)
			(stroke
				(width 0.1)
				(type default)
			)
			(layer "F.Fab")
		)
		(fp_line
			(start 0.67945 0.3048)
			(end 0.120396 0.3048)
			(stroke
				(width 0.1)
				(type default)
			)
			(layer "F.Fab")
		)
		(pad "1" smd circle
			(at -0.40005 0)
			(size 0 0)
			(layers "F.Cu" "F.Mask" "F.Paste")
			(net "SSD2_PWR_EN_R")
		)
		(pad "2" smd circle
			(at 0.40005 0)
			(size 0 0)
			(layers "F.Cu" "F.Mask" "F.Paste")
			(net "GND")
		)
	)
	(footprint ""
		(layer "F.Cu")
		(at 379.754384 -250.070874 -90)
		(property "Reference" "R1409"
			(at 0 0 270)
			(layer "F.SilkS")
			(hide yes)
			(effects
				(font
					(size 1.27 1.27)
				)
			)
		)
		(property "Value" ""
			(at 0 0 270)
			(layer "F.Fab")
			(effects
				(font
					(size 1.27 1.27)
				)
			)
		)
		(duplicate_pad_numbers_are_jumpers no)
		(fp_line
			(start -0.7874 0.4064)
			(end -0.7874 -0.4064)
			(stroke
				(width 0.1524)
				(type default)
			)
			(layer "F.SilkS")
		)
		(fp_line
			(start 0.7874 0.4064)
			(end -0.7874 0.4064)
			(stroke
				(width 0.1524)
				(type default)
			)
			(layer "F.SilkS")
		)
		(fp_line
			(start -0.7874 -0.4064)
			(end 0.7874 -0.4064)
			(stroke
				(width 0.1524)
				(type default)
			)
			(layer "F.SilkS")
		)
		(fp_line
			(start 0.7874 -0.4064)
			(end 0.7874 0.4064)
			(stroke
				(width 0.1524)
				(type default)
			)
			(layer "F.SilkS")
		)
		(fp_line
			(start -0.67945 0.3048)
			(end -0.67945 -0.305054)
			(stroke
				(width 0.1)
				(type default)
			)
			(layer "F.Fab")
		)
		(fp_line
			(start -0.12065 0.3048)
			(end -0.67945 0.3048)
			(stroke
				(width 0.1)
				(type default)
			)
			(layer "F.Fab")
		)
		(fp_line
			(start 0.120396 0.3048)
			(end 0.120396 0.2794)
			(stroke
				(width 0.1)
				(type default)
			)
			(layer "F.Fab")
		)
		(fp_line
			(start 0.67945 0.3048)
			(end 0.120396 0.3048)
			(stroke
				(width 0.1)
				(type default)
			)
			(layer "F.Fab")
		)
		(fp_line
			(start -0.12065 0.2794)
			(end -0.12065 0.3048)
			(stroke
				(width 0.1)
				(type default)
			)
			(layer "F.Fab")
		)
		(fp_line
			(start 0.120396 0.2794)
			(end -0.12065 0.2794)
			(stroke
				(width 0.1)
				(type default)
			)
			(layer "F.Fab")
		)
		(fp_line
			(start -0.12065 -0.2794)
			(end 0.12065 -0.2794)
			(stroke
				(width 0.1)
				(type default)
			)
			(layer "F.Fab")
		)
		(fp_line
			(start 0.12065 -0.2794)
			(end 0.12065 -0.3048)
			(stroke
				(width 0.1)
				(type default)
			)
			(layer "F.Fab")
		)
		(fp_line
			(start 0.12065 -0.3048)
			(end 0.67945 -0.3048)
			(stroke
				(width 0.1)
				(type default)
			)
			(layer "F.Fab")
		)
		(fp_line
			(start 0.67945 -0.3048)
			(end 0.67945 0.3048)
			(stroke
				(width 0.1)
				(type default)
			)
			(layer "F.Fab")
		)
		(fp_line
			(start -0.67945 -0.305054)
			(end -0.12065 -0.305054)
			(stroke
				(width 0.1)
				(type default)
			)
			(layer "F.Fab")
		)
		(fp_line
			(start -0.12065 -0.305054)
			(end -0.12065 -0.2794)
			(stroke
				(width 0.1)
				(type default)
			)
			(layer "F.Fab")
		)
		(pad "1" smd circle
			(at -0.40005 0 270)
			(size 0 0)
			(layers "F.Cu" "F.Mask" "F.Paste")
			(net "PEX3_MODE_SEL4")
		)
		(pad "2" smd circle
			(at 0.40005 0 270)
			(size 0 0)
			(layers "F.Cu" "F.Mask" "F.Paste")
			(net "P1V8_PEX")
		)
	)
	(footprint ""
		(layer "F.Cu")
		(at 167.523668 -167.742108)
		(property "Reference" "C415"
			(at 0 0 0)
			(layer "F.SilkS")
			(hide yes)
			(effects
				(font
					(size 1.27 1.27)
				)
			)
		)
		(property "Value" ""
			(at 0 0 0)
			(layer "F.Fab")
			(effects
				(font
					(size 1.27 1.27)
				)
			)
		)
		(duplicate_pad_numbers_are_jumpers no)
		(fp_line
			(start -0.7874 -0.4064)
			(end 0.7874 -0.4064)
			(stroke
				(width 0.1524)
				(type default)
			)
			(layer "F.SilkS")
		)
		(fp_line
			(start -0.7874 0.4064)
			(end -0.7874 -0.4064)
			(stroke
				(width 0.1524)
				(type default)
			)
			(layer "F.SilkS")
		)
		(fp_line
			(start 0.7874 -0.4064)
			(end 0.7874 0.4064)
			(stroke
				(width 0.1524)
				(type default)
			)
			(layer "F.SilkS")
		)
		(fp_line
			(start 0.7874 0.4064)
			(end -0.7874 0.4064)
			(stroke
				(width 0.1524)
				(type default)
			)
			(layer "F.SilkS")
		)
		(fp_line
			(start -0.67945 -0.305054)
			(end -0.12065 -0.305054)
			(stroke
				(width 0.1)
				(type default)
			)
			(layer "F.Fab")
		)
		(fp_line
			(start -0.67945 0.3048)
			(end -0.67945 -0.305054)
			(stroke
				(width 0.1)
				(type default)
			)
			(layer "F.Fab")
		)
		(fp_line
			(start -0.12065 -0.305054)
			(end -0.12065 -0.2794)
			(stroke
				(width 0.1)
				(type default)
			)
			(layer "F.Fab")
		)
		(fp_line
			(start -0.12065 -0.2794)
			(end 0.12065 -0.2794)
			(stroke
				(width 0.1)
				(type default)
			)
			(layer "F.Fab")
		)
		(fp_line
			(start -0.12065 0.2794)
			(end -0.12065 0.3048)
			(stroke
				(width 0.1)
				(type default)
			)
			(layer "F.Fab")
		)
		(fp_line
			(start -0.12065 0.3048)
			(end -0.67945 0.3048)
			(stroke
				(width 0.1)
				(type default)
			)
			(layer "F.Fab")
		)
		(fp_line
			(start 0.120396 0.2794)
			(end -0.12065 0.2794)
			(stroke
				(width 0.1)
				(type default)
			)
			(layer "F.Fab")
		)
		(fp_line
			(start 0.120396 0.3048)
			(end 0.120396 0.2794)
			(stroke
				(width 0.1)
				(type default)
			)
			(layer "F.Fab")
		)
		(fp_line
			(start 0.12065 -0.3048)
			(end 0.67945 -0.3048)
			(stroke
				(width 0.1)
				(type default)
			)
			(layer "F.Fab")
		)
		(fp_line
			(start 0.12065 -0.2794)
			(end 0.12065 -0.3048)
			(stroke
				(width 0.1)
				(type default)
			)
			(layer "F.Fab")
		)
		(fp_line
			(start 0.67945 -0.3048)
			(end 0.67945 0.3048)
			(stroke
				(width 0.1)
				(type default)
			)
			(layer "F.Fab")
		)
		(fp_line
			(start 0.67945 0.3048)
			(end 0.120396 0.3048)
			(stroke
				(width 0.1)
				(type default)
			)
			(layer "F.Fab")
		)
		(pad "1" smd circle
			(at -0.40005 0)
			(size 0 0)
			(layers "F.Cu" "F.Mask" "F.Paste")
			(net "P3V3_AUX")
		)
		(pad "2" smd circle
			(at 0.40005 0)
			(size 0 0)
			(layers "F.Cu" "F.Mask" "F.Paste")
			(net "GND")
		)
	)
	(footprint ""
		(layer "F.Cu")
		(at 338.796884 -117.627654 180)
		(property "Reference" "PR7026"
			(at 0 0 180)
			(layer "F.SilkS")
			(hide yes)
			(effects
				(font
					(size 1.27 1.27)
				)
			)
		)
		(property "Value" ""
			(at 0 0 180)
			(layer "F.Fab")
			(effects
				(font
					(size 1.27 1.27)
				)
			)
		)
		(duplicate_pad_numbers_are_jumpers no)
		(fp_line
			(start 0.7874 0.4064)
			(end -0.7874 0.4064)
			(stroke
				(width 0.1524)
				(type default)
			)
			(layer "F.SilkS")
		)
		(fp_line
			(start 0.7874 -0.4064)
			(end 0.7874 0.4064)
			(stroke
				(width 0.1524)
				(type default)
			)
			(layer "F.SilkS")
		)
		(fp_line
			(start -0.7874 0.4064)
			(end -0.7874 -0.4064)
			(stroke
				(width 0.1524)
				(type default)
			)
			(layer "F.SilkS")
		)
		(fp_line
			(start -0.7874 -0.4064)
			(end 0.7874 -0.4064)
			(stroke
				(width 0.1524)
				(type default)
			)
			(layer "F.SilkS")
		)
		(fp_line
			(start 0.67945 0.3048)
			(end 0.120396 0.3048)
			(stroke
				(width 0.1)
				(type default)
			)
			(layer "F.Fab")
		)
		(fp_line
			(start 0.67945 -0.3048)
			(end 0.67945 0.3048)
			(stroke
				(width 0.1)
				(type default)
			)
			(layer "F.Fab")
		)
		(fp_line
			(start 0.12065 -0.2794)
			(end 0.12065 -0.3048)
			(stroke
				(width 0.1)
				(type default)
			)
			(layer "F.Fab")
		)
		(fp_line
			(start 0.12065 -0.3048)
			(end 0.67945 -0.3048)
			(stroke
				(width 0.1)
				(type default)
			)
			(layer "F.Fab")
		)
		(fp_line
			(start 0.120396 0.3048)
			(end 0.120396 0.2794)
			(stroke
				(width 0.1)
				(type default)
			)
			(layer "F.Fab")
		)
		(fp_line
			(start 0.120396 0.2794)
			(end -0.12065 0.2794)
			(stroke
				(width 0.1)
				(type default)
			)
			(layer "F.Fab")
		)
		(fp_line
			(start -0.12065 0.3048)
			(end -0.67945 0.3048)
			(stroke
				(width 0.1)
				(type default)
			)
			(layer "F.Fab")
		)
		(fp_line
			(start -0.12065 0.2794)
			(end -0.12065 0.3048)
			(stroke
				(width 0.1)
				(type default)
			)
			(layer "F.Fab")
		)
		(fp_line
			(start -0.12065 -0.2794)
			(end 0.12065 -0.2794)
			(stroke
				(width 0.1)
				(type default)
			)
			(layer "F.Fab")
		)
		(fp_line
			(start -0.12065 -0.305054)
			(end -0.12065 -0.2794)
			(stroke
				(width 0.1)
				(type default)
			)
			(layer "F.Fab")
		)
		(fp_line
			(start -0.67945 0.3048)
			(end -0.67945 -0.305054)
			(stroke
				(width 0.1)
				(type default)
			)
			(layer "F.Fab")
		)
		(fp_line
			(start -0.67945 -0.305054)
			(end -0.12065 -0.305054)
			(stroke
				(width 0.1)
				(type default)
			)
			(layer "F.Fab")
		)
		(pad "1" smd circle
			(at -0.40005 0 180)
			(size 0 0)
			(layers "F.Cu" "F.Mask" "F.Paste")
			(net "P12V_NIC5_CO_OV_FB")
		)
		(pad "2" smd circle
			(at 0.40005 0 180)
			(size 0 0)
			(layers "F.Cu" "F.Mask" "F.Paste")
			(net "P12V_NIC5_R")
		)
	)
)
